(kicad_pcb
	(version 20260206)
	(generator "pcbnew")
	(generator_version "10.0")
	(general
		(thickness 1.6)
		(legacy_teardrops no)
	)
	(paper "A4")
	(title_block
		(title "03242023_DA0F0TMBIJ0_F0T_Motherboard_J_brd_V01_OCP.brd")
		(comment 1 "Grand Teton / footprints 4760-4764 of 6105")
	)
	(layers
		(0 "F.Cu" signal "TOP")
		(4 "In1.Cu" signal "GND")
		(6 "In2.Cu" signal "IN1")
		(8 "In3.Cu" signal "GND1")
		(10 "In4.Cu" signal "IN2")
		(12 "In5.Cu" signal "GND2")
		(14 "In6.Cu" signal "IN3")
		(16 "In7.Cu" signal "GND3")
		(18 "In8.Cu" signal "VCC")
		(20 "In9.Cu" signal "VCC1")
		(22 "In10.Cu" signal "GND4")
		(24 "In11.Cu" signal "IN4")
		(26 "In12.Cu" signal "GND5")
		(28 "In13.Cu" signal "IN5")
		(30 "In14.Cu" signal "GND6")
		(32 "In15.Cu" signal "IN6")
		(34 "In16.Cu" signal "GND7")
		(2 "B.Cu" signal "BOTTOM")
		(9 "F.Adhes" user "F.Adhesive")
		(11 "B.Adhes" user "B.Adhesive")
		(13 "F.Paste" user "Package Geometry/Pastemask Top")
		(15 "B.Paste" user "Package Geometry/Pastemask Bottom")
		(5 "F.SilkS" user "Ref Des/Silkscreen Top")
		(7 "B.SilkS" user "Ref Des/Silkscreen Bottom")
		(1 "F.Mask" user "Board Geometry/Soldermask Top")
		(3 "B.Mask" user "Board Geometry/Soldermask Bottom")
		(17 "Dwgs.User" user "User.Drawings")
		(19 "Cmts.User" user "User.Comments")
		(21 "Eco1.User" user "User.Eco1")
		(23 "Eco2.User" user "User.Eco2")
		(25 "Edge.Cuts" user "Board Geometry/Outline")
		(27 "Margin" user)
		(31 "F.CrtYd" user "Package Geometry/Place Bound Top")
		(29 "B.CrtYd" user "Package Geometry/Place Bound Bottom")
		(35 "F.Fab" user "Ref Des/Assembly Top")
		(33 "B.Fab" user "Ref Des/Assembly Bottom")
	)
	(footprint ""
		(layer "B.Cu")
		(at 178.120802 -104.71277 180)
		(property "Reference" "R1302"
			(at 0 0 0)
			(layer "B.SilkS")
			(hide yes)
			(effects
				(font
					(size 1.27 1.27)
				)
				(justify mirror)
			)
		)
		(property "Value" ""
			(at 0 0 0)
			(layer "B.Fab")
			(effects
				(font
					(size 1.27 1.27)
				)
				(justify mirror)
			)
		)
		(duplicate_pad_numbers_are_jumpers no)
		(fp_line
			(start 0.7874 0.4064)
			(end 0.7874 -0.4064)
			(stroke
				(width 0.1524)
				(type default)
			)
			(layer "B.SilkS")
		)
		(fp_line
			(start 0.7874 -0.4064)
			(end -0.7874 -0.4064)
			(stroke
				(width 0.1524)
				(type default)
			)
			(layer "B.SilkS")
		)
		(fp_line
			(start -0.7874 0.4064)
			(end 0.7874 0.4064)
			(stroke
				(width 0.1524)
				(type default)
			)
			(layer "B.SilkS")
		)
		(fp_line
			(start -0.7874 -0.4064)
			(end -0.7874 0.4064)
			(stroke
				(width 0.1524)
				(type default)
			)
			(layer "B.SilkS")
		)
		(fp_line
			(start 0.67945 0.3048)
			(end 0.67945 -0.305054)
			(stroke
				(width 0.1)
				(type default)
			)
			(layer "B.Fab")
		)
		(fp_line
			(start 0.67945 -0.305054)
			(end 0.12065 -0.305054)
			(stroke
				(width 0.1)
				(type default)
			)
			(layer "B.Fab")
		)
		(fp_line
			(start 0.12065 0.3048)
			(end 0.67945 0.3048)
			(stroke
				(width 0.1)
				(type default)
			)
			(layer "B.Fab")
		)
		(fp_line
			(start 0.12065 0.2794)
			(end 0.12065 0.3048)
			(stroke
				(width 0.1)
				(type default)
			)
			(layer "B.Fab")
		)
		(fp_line
			(start 0.12065 -0.2794)
			(end -0.12065 -0.2794)
			(stroke
				(width 0.1)
				(type default)
			)
			(layer "B.Fab")
		)
		(fp_line
			(start 0.12065 -0.305054)
			(end 0.12065 -0.2794)
			(stroke
				(width 0.1)
				(type default)
			)
			(layer "B.Fab")
		)
		(fp_line
			(start -0.120396 0.3048)
			(end -0.120396 0.2794)
			(stroke
				(width 0.1)
				(type default)
			)
			(layer "B.Fab")
		)
		(fp_line
			(start -0.120396 0.2794)
			(end 0.12065 0.2794)
			(stroke
				(width 0.1)
				(type default)
			)
			(layer "B.Fab")
		)
		(fp_line
			(start -0.12065 -0.2794)
			(end -0.12065 -0.3048)
			(stroke
				(width 0.1)
				(type default)
			)
			(layer "B.Fab")
		)
		(fp_line
			(start -0.12065 -0.3048)
			(end -0.67945 -0.3048)
			(stroke
				(width 0.1)
				(type default)
			)
			(layer "B.Fab")
		)
		(fp_line
			(start -0.67945 0.3048)
			(end -0.120396 0.3048)
			(stroke
				(width 0.1)
				(type default)
			)
			(layer "B.Fab")
		)
		(fp_line
			(start -0.67945 -0.3048)
			(end -0.67945 0.3048)
			(stroke
				(width 0.1)
				(type default)
			)
			(layer "B.Fab")
		)
		(pad "1" smd circle
			(at 0.40005 0)
			(size 0 0)
			(layers "B.Cu" "B.Mask" "B.Paste")
			(net "PWRGD_DRAMPWRGD_CPU0_AB_R_LVC1")
		)
		(pad "2" smd circle
			(at -0.40005 0)
			(size 0 0)
			(layers "B.Cu" "B.Mask" "B.Paste")
			(net "GND")
		)
	)
	(footprint ""
		(layer "B.Cu")
		(at 485.20985 -211.012532 -90)
		(property "Reference" "X37"
			(at -0.442468 -2.18948 270)
			(unlocked yes)
			(layer "B.SilkS")
			(effects
				(font
					(size 0.7874 0.5842)
					(thickness 0.1524)
				)
				(justify left mirror)
			)
		)
		(property "Value" ""
			(at 0 0 90)
			(layer "B.Fab")
			(effects
				(font
					(size 1.27 1.27)
				)
				(justify mirror)
			)
		)
		(property "Device Type" "TP_TDR_4P_FTS_TH-TP_TDR_4P_DIPA"
			(at -1.30175 1.27 180)
			(unlocked yes)
			(layer "B.Fab")
			(hide yes)
			(effects
				(font
					(size 0.635 0.4064)
					(thickness 0.1524)
				)
				(justify mirror)
			)
		)
		(property "User Part Number" "N_A"
			(at -1.30175 1.27 180)
			(unlocked yes)
			(layer "Cmts.User")
			(hide yes)
			(effects
				(font
					(size 0.635 0.4064)
					(thickness 0.1524)
				)
				(justify mirror)
			)
		)
		(duplicate_pad_numbers_are_jumpers no)
		(fp_line
			(start -2.54 3.81)
			(end -2.54 3.6703)
			(stroke
				(width 0.1524)
				(type default)
			)
			(layer "B.SilkS")
		)
		(fp_line
			(start 0 3.81)
			(end -2.54 3.81)
			(stroke
				(width 0.1524)
				(type default)
			)
			(layer "B.SilkS")
		)
		(fp_line
			(start 0 3.175)
			(end 0 3.81)
			(stroke
				(width 0.1524)
				(type default)
			)
			(layer "B.SilkS")
		)
		(fp_line
			(start -2.54 1.4097)
			(end -2.54 1.1303)
			(stroke
				(width 0.1524)
				(type default)
			)
			(layer "B.SilkS")
		)
		(fp_line
			(start 0 0.635)
			(end 0 1.905)
			(stroke
				(width 0.1524)
				(type default)
			)
			(layer "B.SilkS")
		)
		(fp_line
			(start -2.54 -1.1303)
			(end -2.54 -1.27)
			(stroke
				(width 0.1524)
				(type default)
			)
			(layer "B.SilkS")
		)
		(fp_line
			(start -2.54 -1.27)
			(end 0 -1.27)
			(stroke
				(width 0.1524)
				(type default)
			)
			(layer "B.SilkS")
		)
		(fp_line
			(start 0 -1.27)
			(end 0 -0.635)
			(stroke
				(width 0.1524)
				(type default)
			)
			(layer "B.SilkS")
		)
		(fp_poly
			(pts
				(xy 0.761746 0) (xy 2.285746 -0.762) (xy 2.285746 0.762)
			)
			(stroke
				(width 0)
				(type default)
			)
			(fill yes)
			(layer "B.SilkS")
		)
		(fp_line
			(start -2.54 3.81)
			(end -2.54 -1.27)
			(stroke
				(width 0.1)
				(type default)
			)
			(layer "B.Fab")
		)
		(fp_line
			(start 0 3.81)
			(end -2.54 3.81)
			(stroke
				(width 0.1)
				(type default)
			)
			(layer "B.Fab")
		)
		(fp_line
			(start -2.54 -1.27)
			(end 0 -1.27)
			(stroke
				(width 0.1)
				(type default)
			)
			(layer "B.Fab")
		)
		(fp_line
			(start 0 -1.27)
			(end 0 3.81)
			(stroke
				(width 0.1)
				(type default)
			)
			(layer "B.Fab")
		)
		(fp_poly
			(pts
				(xy 0.761746 0) (xy 2.285746 -0.762) (xy 2.285746 0.762)
			)
			(stroke
				(width 0)
				(type default)
			)
			(fill yes)
			(layer "B.Fab")
		)
		(pad "1" thru_hole circle
			(at 0 0 90)
			(size 1.0033 1.0033)
			(drill 0.249936)
			(layers "*.Cu" "*.Mask")
			(remove_unused_layers no)
			(net "TDR_DIFF_85_NECK_IN4_DP")
			(clearance 0.10795)
			(padstack
				(mode front_inner_back)
				(layer "Inner"
					(shape circle)
					(size 0.8001 0.8001)
					(clearance 0.1524)
				)
				(layer "B.Cu"
					(shape circle)
					(size 1.0033 1.0033)
					(thermal_gap 0.10795)
					(clearance 0.10795)
				)
			)
		)
		(pad "2" thru_hole circle
			(at -2.54 0 90)
			(size 1.9939 1.9939)
			(drill 0.249936)
			(layers "*.Cu" "*.Mask")
			(remove_unused_layers no)
			(net "T1_GND")
			(clearance 0.10795)
			(padstack
				(mode front_inner_back)
				(layer "Inner"
					(shape circle)
					(size 0.8001 0.8001)
					(clearance 0.1524)
				)
				(layer "B.Cu"
					(shape circle)
					(size 1.9939 1.9939)
					(thermal_gap 0.10795)
					(clearance 0.10795)
				)
			)
		)
		(pad "3" thru_hole circle
			(at -2.54 2.54 90)
			(size 1.9939 1.9939)
			(drill 0.249936)
			(layers "*.Cu" "*.Mask")
			(remove_unused_layers no)
			(net "T1_GND")
			(clearance 0.10795)
			(padstack
				(mode front_inner_back)
				(layer "Inner"
					(shape circle)
					(size 0.8001 0.8001)
					(clearance 0.1524)
				)
				(layer "B.Cu"
					(shape circle)
					(size 1.9939 1.9939)
					(thermal_gap 0.10795)
					(clearance 0.10795)
				)
			)
		)
		(pad "4" thru_hole circle
			(at 0 2.54 90)
			(size 1.0033 1.0033)
			(drill 0.249936)
			(layers "*.Cu" "*.Mask")
			(remove_unused_layers no)
			(net "TDR_DIFF_85_NECK_IN4_DN")
			(clearance 0.10795)
			(padstack
				(mode front_inner_back)
				(layer "Inner"
					(shape circle)
					(size 0.8001 0.8001)
					(clearance 0.1524)
				)
				(layer "B.Cu"
					(shape circle)
					(size 1.0033 1.0033)
					(thermal_gap 0.10795)
					(clearance 0.10795)
				)
			)
		)
	)
	(footprint ""
		(layer "B.Cu")
		(at 452.01205 -3.866388 -90)
		(property "Reference" "R1504"
			(at 0 0 90)
			(layer "B.SilkS")
			(hide yes)
			(effects
				(font
					(size 1.27 1.27)
				)
				(justify mirror)
			)
		)
		(property "Value" ""
			(at 0 0 90)
			(layer "B.Fab")
			(effects
				(font
					(size 1.27 1.27)
				)
				(justify mirror)
			)
		)
		(duplicate_pad_numbers_are_jumpers no)
		(fp_line
			(start -0.7874 0.4064)
			(end 0.7874 0.4064)
			(stroke
				(width 0.1524)
				(type default)
			)
			(layer "B.SilkS")
		)
		(fp_line
			(start 0.7874 0.4064)
			(end 0.7874 -0.4064)
			(stroke
				(width 0.1524)
				(type default)
			)
			(layer "B.SilkS")
		)
		(fp_line
			(start -0.7874 -0.4064)
			(end -0.7874 0.4064)
			(stroke
				(width 0.1524)
				(type default)
			)
			(layer "B.SilkS")
		)
		(fp_line
			(start 0.7874 -0.4064)
			(end -0.7874 -0.4064)
			(stroke
				(width 0.1524)
				(type default)
			)
			(layer "B.SilkS")
		)
		(fp_line
			(start -0.67945 0.3048)
			(end -0.120396 0.3048)
			(stroke
				(width 0.1)
				(type default)
			)
			(layer "B.Fab")
		)
		(fp_line
			(start -0.120396 0.3048)
			(end -0.120396 0.2794)
			(stroke
				(width 0.1)
				(type default)
			)
			(layer "B.Fab")
		)
		(fp_line
			(start 0.12065 0.3048)
			(end 0.67945 0.3048)
			(stroke
				(width 0.1)
				(type default)
			)
			(layer "B.Fab")
		)
		(fp_line
			(start 0.67945 0.3048)
			(end 0.67945 -0.305054)
			(stroke
				(width 0.1)
				(type default)
			)
			(layer "B.Fab")
		)
		(fp_line
			(start -0.120396 0.2794)
			(end 0.12065 0.2794)
			(stroke
				(width 0.1)
				(type default)
			)
			(layer "B.Fab")
		)
		(fp_line
			(start 0.12065 0.2794)
			(end 0.12065 0.3048)
			(stroke
				(width 0.1)
				(type default)
			)
			(layer "B.Fab")
		)
		(fp_line
			(start -0.12065 -0.2794)
			(end -0.12065 -0.3048)
			(stroke
				(width 0.1)
				(type default)
			)
			(layer "B.Fab")
		)
		(fp_line
			(start 0.12065 -0.2794)
			(end -0.12065 -0.2794)
			(stroke
				(width 0.1)
				(type default)
			)
			(layer "B.Fab")
		)
		(fp_line
			(start -0.67945 -0.3048)
			(end -0.67945 0.3048)
			(stroke
				(width 0.1)
				(type default)
			)
			(layer "B.Fab")
		)
		(fp_line
			(start -0.12065 -0.3048)
			(end -0.67945 -0.3048)
			(stroke
				(width 0.1)
				(type default)
			)
			(layer "B.Fab")
		)
		(fp_line
			(start 0.12065 -0.305054)
			(end 0.12065 -0.2794)
			(stroke
				(width 0.1)
				(type default)
			)
			(layer "B.Fab")
		)
		(fp_line
			(start 0.67945 -0.305054)
			(end 0.12065 -0.305054)
			(stroke
				(width 0.1)
				(type default)
			)
			(layer "B.Fab")
		)
		(pad "1" smd circle
			(at 0.40005 0 90)
			(size 0 0)
			(layers "B.Cu" "B.Mask" "B.Paste")
			(net "RST_OCP_V3_1_BUF_N")
		)
		(pad "2" smd circle
			(at -0.40005 0 90)
			(size 0 0)
			(layers "B.Cu" "B.Mask" "B.Paste")
			(net "RST_PERST2_OCP_SFF_N")
		)
	)
	(footprint ""
		(layer "B.Cu")
		(at 336.269584 -58.486548 -90)
		(property "Reference" "C1202"
			(at 0 0 90)
			(layer "B.SilkS")
			(hide yes)
			(effects
				(font
					(size 1.27 1.27)
				)
				(justify mirror)
			)
		)
		(property "Value" ""
			(at 0 0 90)
			(layer "B.Fab")
			(effects
				(font
					(size 1.27 1.27)
				)
				(justify mirror)
			)
		)
		(duplicate_pad_numbers_are_jumpers no)
		(fp_line
			(start -1.2954 0.5842)
			(end 1.2954 0.5842)
			(stroke
				(width 0.1524)
				(type default)
			)
			(layer "B.SilkS")
		)
		(fp_line
			(start 1.2954 0.5842)
			(end 1.2954 -0.5842)
			(stroke
				(width 0.1524)
				(type default)
			)
			(layer "B.SilkS")
		)
		(fp_line
			(start -1.2954 -0.5842)
			(end -1.2954 0.5842)
			(stroke
				(width 0.1524)
				(type default)
			)
			(layer "B.SilkS")
		)
		(fp_line
			(start 0 -0.5842)
			(end 0 0.5842)
			(stroke
				(width 0.1524)
				(type default)
			)
			(layer "B.SilkS")
		)
		(fp_line
			(start 1.2954 -0.5842)
			(end -1.2954 -0.5842)
			(stroke
				(width 0.1524)
				(type default)
			)
			(layer "B.SilkS")
		)
		(fp_line
			(start -0.8636 0.4572)
			(end 0.8636 0.4572)
			(stroke
				(width 0.1)
				(type default)
			)
			(layer "B.Fab")
		)
		(fp_line
			(start 0.8636 0.4572)
			(end 0.8636 0.4064)
			(stroke
				(width 0.1)
				(type default)
			)
			(layer "B.Fab")
		)
		(fp_line
			(start -1.1938 0.4064)
			(end -0.8636 0.4064)
			(stroke
				(width 0.1)
				(type default)
			)
			(layer "B.Fab")
		)
		(fp_line
			(start -0.8636 0.4064)
			(end -0.8636 0.4572)
			(stroke
				(width 0.1)
				(type default)
			)
			(layer "B.Fab")
		)
		(fp_line
			(start 0.8636 0.4064)
			(end 1.1938 0.4064)
			(stroke
				(width 0.1)
				(type default)
			)
			(layer "B.Fab")
		)
		(fp_line
			(start 1.1938 0.4064)
			(end 1.1938 -0.4064)
			(stroke
				(width 0.1)
				(type default)
			)
			(layer "B.Fab")
		)
		(fp_line
			(start -1.1938 -0.4064)
			(end -1.1938 0.4064)
			(stroke
				(width 0.1)
				(type default)
			)
			(layer "B.Fab")
		)
		(fp_line
			(start -0.8636 -0.4064)
			(end -1.1938 -0.4064)
			(stroke
				(width 0.1)
				(type default)
			)
			(layer "B.Fab")
		)
		(fp_line
			(start 0.8636 -0.4064)
			(end 0.8636 -0.4572)
			(stroke
				(width 0.1)
				(type default)
			)
			(layer "B.Fab")
		)
		(fp_line
			(start 1.1938 -0.4064)
			(end 0.8636 -0.4064)
			(stroke
				(width 0.1)
				(type default)
			)
			(layer "B.Fab")
		)
		(fp_line
			(start -0.8636 -0.4572)
			(end -0.8636 -0.4064)
			(stroke
				(width 0.1)
				(type default)
			)
			(layer "B.Fab")
		)
		(fp_line
			(start 0.8636 -0.4572)
			(end -0.8636 -0.4572)
			(stroke
				(width 0.1)
				(type default)
			)
			(layer "B.Fab")
		)
		(pad "1" smd rect
			(at 0.7366 0 180)
			(size 0.7112 0.8128)
			(layers "B.Cu" "B.Mask" "B.Paste")
			(net "P1V8_PCH_AUX")
		)
		(pad "2" smd rect
			(at -0.7366 0 180)
			(size 0.7112 0.8128)
			(layers "B.Cu" "B.Mask" "B.Paste")
			(net "GND")
		)
	)
	(footprint ""
		(layer "B.Cu")
		(at 292.528498 -403.031452 90)
		(property "Reference" "PR2518"
			(at 0 0 90)
			(layer "B.SilkS")
			(hide yes)
			(effects
				(font
					(size 1.27 1.27)
				)
				(justify mirror)
			)
		)
		(property "Value" ""
			(at 0 0 90)
			(layer "B.Fab")
			(effects
				(font
					(size 1.27 1.27)
				)
				(justify mirror)
			)
		)
		(duplicate_pad_numbers_are_jumpers no)
		(fp_line
			(start 0.7874 -0.4064)
			(end -0.7874 -0.4064)
			(stroke
				(width 0.1524)
				(type default)
			)
			(layer "B.SilkS")
		)
		(fp_line
			(start -0.7874 -0.4064)
			(end -0.7874 0.4064)
			(stroke
				(width 0.1524)
				(type default)
			)
			(layer "B.SilkS")
		)
		(fp_line
			(start 0.7874 0.4064)
			(end 0.7874 -0.4064)
			(stroke
				(width 0.1524)
				(type default)
			)
			(layer "B.SilkS")
		)
		(fp_line
			(start -0.7874 0.4064)
			(end 0.7874 0.4064)
			(stroke
				(width 0.1524)
				(type default)
			)
			(layer "B.SilkS")
		)
		(fp_line
			(start 0.67945 -0.305054)
			(end 0.12065 -0.305054)
			(stroke
				(width 0.1)
				(type default)
			)
			(layer "B.Fab")
		)
		(fp_line
			(start 0.12065 -0.305054)
			(end 0.12065 -0.2794)
			(stroke
				(width 0.1)
				(type default)
			)
			(layer "B.Fab")
		)
		(fp_line
			(start -0.12065 -0.3048)
			(end -0.67945 -0.3048)
			(stroke
				(width 0.1)
				(type default)
			)
			(layer "B.Fab")
		)
		(fp_line
			(start -0.67945 -0.3048)
			(end -0.67945 0.3048)
			(stroke
				(width 0.1)
				(type default)
			)
			(layer "B.Fab")
		)
		(fp_line
			(start 0.12065 -0.2794)
			(end -0.12065 -0.2794)
			(stroke
				(width 0.1)
				(type default)
			)
			(layer "B.Fab")
		)
		(fp_line
			(start -0.12065 -0.2794)
			(end -0.12065 -0.3048)
			(stroke
				(width 0.1)
				(type default)
			)
			(layer "B.Fab")
		)
		(fp_line
			(start 0.12065 0.2794)
			(end 0.12065 0.3048)
			(stroke
				(width 0.1)
				(type default)
			)
			(layer "B.Fab")
		)
		(fp_line
			(start -0.120396 0.2794)
			(end 0.12065 0.2794)
			(stroke
				(width 0.1)
				(type default)
			)
			(layer "B.Fab")
		)
		(fp_line
			(start 0.67945 0.3048)
			(end 0.67945 -0.305054)
			(stroke
				(width 0.1)
				(type default)
			)
			(layer "B.Fab")
		)
		(fp_line
			(start 0.12065 0.3048)
			(end 0.67945 0.3048)
			(stroke
				(width 0.1)
				(type default)
			)
			(layer "B.Fab")
		)
		(fp_line
			(start -0.120396 0.3048)
			(end -0.120396 0.2794)
			(stroke
				(width 0.1)
				(type default)
			)
			(layer "B.Fab")
		)
		(fp_line
			(start -0.67945 0.3048)
			(end -0.120396 0.3048)
			(stroke
				(width 0.1)
				(type default)
			)
			(layer "B.Fab")
		)
		(pad "1" smd circle
			(at 0.40005 0 270)
			(size 0 0)
			(layers "B.Cu" "B.Mask" "B.Paste")
			(net "P12V_HSC_ADC_N")
		)
		(pad "2" smd circle
			(at -0.40005 0 270)
			(size 0 0)
			(layers "B.Cu" "B.Mask" "B.Paste")
			(net "P12V_HSC_SENSE2_R4_N")
		)
	)
)
